# BASEBOARD_FAB2 (Tioga Pass) — schematic netlist excerpt (pin names and nets, part order shuffled) for the footprints in the layout excerpt that follows; sources: Cadence DE-HDL packaged netlist, KiCad conversion of Wiwynn_Tioga_Pass_MB.brd

J9U2  SCONN288_H44441003  SCONN  pkg PIP  page 82
  \12v\(1)  = P12V_NVDIMM_GHJ
  VSS(93)  = GND
  DQ(4)  = M_J_DQ<4>
  VSS(92)  = GND
  DQ(0)  = M_J_DQ<0>
  VSS(91)  = GND
  DQS9P  = M_J_DQS_DP<9>
  DQS9N  = M_J_DQS_DN<9>
  VSS(90)  = GND
  DQ(6)  = M_J_DQ<6>
  VSS(89)  = GND
  DQ(2)  = M_J_DQ<2>
  VSS(88)  = GND
  DQ(12)  = M_J_DQ<12>
  VSS(87)  = GND
  DQ(8)  = M_J_DQ<8>
  VSS(86)  = GND
  DQS10P  = M_J_DQS_DP<10>
  DQS10N  = M_J_DQS_DN<10>
  VSS(85)  = GND
  DQ(14)  = M_J_DQ<14>
  VSS(84)  = GND
  DQ(10)  = M_J_DQ<10>
  VSS(83)  = GND
  DQ(20)  = M_J_DQ<20>
  VSS(82)  = GND
  DQ(16)  = M_J_DQ<16>
  VSS(81)  = GND
  DQS11P  = M_J_DQS_DP<11>
  DQS11N  = M_J_DQS_DN<11>
  VSS(80)  = GND
  DQ(22)  = M_J_DQ<22>
  VSS(79)  = GND
  DQ(18)  = M_J_DQ<18>
  VSS(78)  = GND
  DQ(28)  = M_J_DQ<28>
  VSS(77)  = GND
  DQ(24)  = M_J_DQ<24>
  VSS(76)  = GND
  DQS12P  = M_J_DQS_DP<12>
  DQS12N  = M_J_DQS_DN<12>
  VSS(75)  = GND
  DQ(30)  = M_J_DQ<30>
  VSS(74)  = GND
  DQ(26)  = M_J_DQ<26>
  VSS(73)  = GND
  CB(4)  = M_J_ECC<4>
  VSS(72)  = GND
  CB(0)  = M_J_ECC<0>
  VSS(71)  = GND
  DQS17P  = M_J_DQS_DP<17>
  DQS17N  = M_J_DQS_DN<17>
  VSS(70)  = GND
  CB(6)  = M_J_ECC<6>
  VSS(69)  = GND
  CB(2)  = M_J_ECC<2>
  VSS(68)  = GND
  RESET_N  = M_GHJ_RST_N
  VDD(25)  = PVDDQ_GHJ
  CKE(0)  = M_J_CKE<2>
  VDD(24)  = PVDDQ_GHJ
  ACT_N  = M_J_ACT_N
  BG(0)  = M_J_BG<0>
  VDD(23)  = PVDDQ_GHJ
  A12  = M_J_MA<12>
  A9  = M_J_MA<9>
  VDD(22)  = PVDDQ_GHJ
  A8  = M_J_MA<8>
  A6  = M_J_MA<6>
  VDD(21)  = PVDDQ_GHJ
  A3  = M_J_MA<3>
  A1  = M_J_MA<1>
  VDD(20)  = PVDDQ_GHJ
  CK0P  = M_J_CLK_DP<2>
  CK0N  = M_J_CLK_DN<2>
  VDD(19)  = PVDDQ_GHJ
  VTT(1)  = PVTT_GHJ
  EVENT_N  = FM_DIMM_EVENT_COD_N
  A0  = M_J_MA<0>
  VDD(18)  = PVDDQ_GHJ
  BA(0)  = M_J_BA<0>
  A16_RAS_N  = M_J_MA<16>
  VDD(17)  = PVDDQ_GHJ
  S0_N  = M_J_CS_N<4>
  VDD(16)  = PVDDQ_GHJ
  A15_CAS_N  = M_J_MA<15>
  ODT(0)  = M_J_ODT<2>
  VDD(15)  = PVDDQ_GHJ
  S1_N  = M_J_CS_N<5>
  VDD(14)  = PVDDQ_GHJ
  ODT(1)  = M_J_ODT<3>
  VDD(13)  = PVDDQ_GHJ
  S2_N_C(0)  = M_J_CS_N<6>
  VSS(67)  = GND
  DQ(36)  = M_J_DQ<36>
  VSS(66)  = GND
  DQ(32)  = M_J_DQ<32>
  VSS(65)  = GND
  DQS13P  = M_J_DQS_DP<13>
  DQS13N  = M_J_DQS_DN<13>
  VSS(64)  = GND
  DQ(38)  = M_J_DQ<38>
  VSS(63)  = GND
  DQ(34)  = M_J_DQ<34>
  VSS(62)  = GND
  DQ(44)  = M_J_DQ<44>
  VSS(61)  = GND
  DQ(40)  = M_J_DQ<40>
  VSS(60)  = GND
  DQS14P  = M_J_DQS_DP<14>
  DQS14N  = M_J_DQS_DN<14>
  VSS(59)  = GND
  DQ(46)  = M_J_DQ<46>
  VSS(58)  = GND
  DQ(42)  = M_J_DQ<42>
  VSS(57)  = GND
  DQ(52)  = M_J_DQ<52>
  VSS(56)  = GND
  DQ(48)  = M_J_DQ<48>
  VSS(55)  = GND
  DQS15P  = M_J_DQS_DP<15>
  DQS15N  = M_J_DQS_DN<15>
  VSS(54)  = GND
  DQ(54)  = M_J_DQ<54>
  VSS(53)  = GND
  DQ(50)  = M_J_DQ<50>
  VSS(52)  = GND
  DQ(60)  = M_J_DQ<60>
  VSS(51)  = GND
  DQ(56)  = M_J_DQ<56>
  VSS(50)  = GND
  DQS16P  = M_J_DQS_DP<16>
  DQS16N  = M_J_DQS_DN<16>
  VSS(49)  = GND
  DQ(62)  = M_J_DQ<62>
  VSS(48)  = GND
  DQ(58)  = M_J_DQ<58>
  VSS(47)  = GND
  SA(0)  = PVPP_GHJ
  SA(1)  = GND
  SCL  = SMB_DDR_GHJ_VPP_SCL
  VPP(4)  = PVPP_GHJ
  VPP(3)  = PVPP_GHJ
  RFU(2)  = TP_CH_J_DIMM_J1_RFU_2
  \12v\(0)  = P12V_NVDIMM_GHJ
  VREFCA  = M_J_VREF
  VSS(46)  = GND
  DQ(5)  = M_J_DQ<5>
  VSS(45)  = GND
  DQ(1)  = M_J_DQ<1>
  VSS(44)  = GND
  DQS0N  = M_J_DQS_DN<0>
  DQS0P  = M_J_DQS_DP<0>
  VSS(43)  = GND
  DQ(7)  = M_J_DQ<7>
  VSS(42)  = GND
  DQ(3)  = M_J_DQ<3>
  VSS(41)  = GND
  DQ(13)  = M_J_DQ<13>
  VSS(40)  = GND
  DQ(9)  = M_J_DQ<9>
  VSS(39)  = GND
  DQS1N  = M_J_DQS_DN<1>
  DQS1P  = M_J_DQS_DP<1>
  VSS(38)  = GND
  DQ(15)  = M_J_DQ<15>
  VSS(37)  = GND
  DQ(11)  = M_J_DQ<11>
  VSS(36)  = GND
  DQ(21)  = M_J_DQ<21>
  VSS(35)  = GND
  DQ(17)  = M_J_DQ<17>
  VSS(34)  = GND
  DQS2N  = M_J_DQS_DN<2>
  DQS2P  = M_J_DQS_DP<2>
  VSS(33)  = GND
  DQ(23)  = M_J_DQ<23>
  VSS(32)  = GND
  DQ(19)  = M_J_DQ<19>
  VSS(31)  = GND
  DQ(29)  = M_J_DQ<29>
  VSS(30)  = GND
  DQ(25)  = M_J_DQ<25>
  VSS(29)  = GND
  DQS3N  = M_J_DQS_DN<3>
  DQS3P  = M_J_DQS_DP<3>
  VSS(28)  = GND
  DQ(31)  = M_J_DQ<31>
  VSS(27)  = GND
  DQ(27)  = M_J_DQ<27>
  VSS(26)  = GND
  CB(5)  = M_J_ECC<5>
  VSS(25)  = GND
  CB(1)  = M_J_ECC<1>
  VSS(24)  = GND
  DQS8N  = M_J_DQS_DN<8>
  DQS8P  = M_J_DQS_DP<8>
  VSS(23)  = GND
  CB(7)  = M_J_ECC<7>
  VSS(22)  = GND
  CB(3)  = M_J_ECC<3>
  VSS(21)  = GND
  CKE(1)  = M_J_CKE<3>
  VDD(12)  = PVDDQ_GHJ
  RFU(0)  = TP_CH_J_DIMM_J1_RFU_0
  VDD(11)  = PVDDQ_GHJ
  BG(1)  = M_J_BG<1>
  ALERT_N  = M_J_ALERT_N
  VDD(10)  = PVDDQ_GHJ
  A11  = M_J_MA<11>
  A7  = M_J_MA<7>
  VDD(9)  = PVDDQ_GHJ
  A5  = M_J_MA<5>
  A4  = M_J_MA<4>
  VDD(8)  = PVDDQ_GHJ
  A2  = M_J_MA<2>
  VDD(7)  = PVDDQ_GHJ
  CK1P  = M_J_CLK_DP<3>
  CK1N  = M_J_CLK_DN<3>
  VDD(6)  = PVDDQ_GHJ
  VTT(0)  = PVTT_GHJ
  PAR  = M_J_PAR
  VDD(5)  = PVDDQ_GHJ
  BA(1)  = M_J_BA<1>
  A10  = M_J_MA<10>
  VDD(4)  = PVDDQ_GHJ
  RFU(1)  = TP_CH_J_DIMM_J1_RFU_1
  A14_WE_N  = M_J_MA<14>
  VDD(3)  = PVDDQ_GHJ
  SAVE_N_NC  = FM_ADR_COMPLETE_GHJ_N
  VDD(2)  = PVDDQ_GHJ
  A13  = M_J_MA<13>
  VDD(1)  = PVDDQ_GHJ
  A17  = M_J_MA<17>
  C(2)  = M_J_C<2>
  VDD(0)  = PVDDQ_GHJ
  S3_N_C(1)  = M_J_CS_N<7>
  SA(2)  = PVPP_GHJ
  VSS(20)  = GND
  DQ(37)  = M_J_DQ<37>
  VSS(19)  = GND
  DQ(33)  = M_J_DQ<33>
  VSS(18)  = GND
  DQS4N  = M_J_DQS_DN<4>
  DQS4P  = M_J_DQS_DP<4>
  VSS(17)  = GND
  DQ(39)  = M_J_DQ<39>
  VSS(16)  = GND
  DQ(35)  = M_J_DQ<35>
  VSS(15)  = GND
  DQ(45)  = M_J_DQ<45>
  VSS(14)  = GND
  DQ(41)  = M_J_DQ<41>
  VSS(13)  = GND
  DQS5N  = M_J_DQS_DN<5>
  DQS5P  = M_J_DQS_DP<5>
  VSS(12)  = GND
  DQ(47)  = M_J_DQ<47>
  VSS(11)  = GND
  DQ(43)  = M_J_DQ<43>
  VSS(10)  = GND
  DQ(53)  = M_J_DQ<53>
  VSS(9)  = GND
  DQ(49)  = M_J_DQ<49>
  VSS(8)  = GND
  DQS6N  = M_J_DQS_DN<6>
  DQS6P  = M_J_DQS_DP<6>
  VSS(7)  = GND
  DQ(55)  = M_J_DQ<55>
  VSS(6)  = GND
  DQ(51)  = M_J_DQ<51>
  VSS(5)  = GND
  DQ(61)  = M_J_DQ<61>
  VSS(4)  = GND
  DQ(57)  = M_J_DQ<57>
  VSS(3)  = GND
  DQS7N  = M_J_DQS_DN<7>
  DQS7P  = M_J_DQS_DP<7>
  VSS(2)  = GND
  DQ(63)  = M_J_DQ<63>
  VSS(1)  = GND
  DQ(59)  = M_J_DQ<59>
  VSS(0)  = GND
  VDDSPD  = PVPP_GHJ
  SDA  = SMB_DDR_GHJ_VPP_SDA
  VPP(1)  = PVPP_GHJ
  VPP(0)  = PVPP_GHJ
  VPP(2)  = PVPP_GHJ

(kicad_pcb
	(version 20260206)
	(generator "pcbnew")
	(generator_version "10.0")
	(general
		(thickness 1.6)
		(legacy_teardrops no)
	)
	(paper "A4")
	(title_block
		(title "Wiwynn_Tioga_Pass_MB.brd")
		(comment 1 "Tioga Pass / footprint 4543 of 4770 (J9U2), pads 152-201 of 291")
	)
	(layers
		(0 "F.Cu" signal "TOP")
		(4 "In1.Cu" signal "L2GND")
		(6 "In2.Cu" signal "L3")
		(8 "In3.Cu" signal "L4GND")
		(10 "In4.Cu" signal "L5")
		(12 "In5.Cu" signal "L6GND")
		(14 "In6.Cu" signal "L7VCC")
		(16 "In7.Cu" signal "L8VCC")
		(18 "In8.Cu" signal "L9GND")
		(20 "In9.Cu" signal "L10")
		(22 "In10.Cu" signal "L11GND")
		(24 "In11.Cu" signal "L12")
		(26 "In12.Cu" signal "L13GND")
		(2 "B.Cu" signal "BOTTOM")
		(9 "F.Adhes" user "F.Adhesive")
		(11 "B.Adhes" user "B.Adhesive")
		(13 "F.Paste" user "Package Geometry/Pastemask Top")
		(15 "B.Paste" user "Package Geometry/Pastemask Bottom")
		(5 "F.SilkS" user "Ref Des/Silkscreen Top")
		(7 "B.SilkS" user "Ref Des/Silkscreen Bottom")
		(1 "F.Mask" user "Board Geometry/Soldermask Top")
		(3 "B.Mask" user "Board Geometry/Soldermask Bottom")
		(17 "Dwgs.User" user "User.Drawings")
		(19 "Cmts.User" user "User.Comments")
		(21 "Eco1.User" user "User.Eco1")
		(23 "Eco2.User" user "User.Eco2")
		(25 "Edge.Cuts" user "Board Geometry/Outline")
		(27 "Margin" user)
		(31 "F.CrtYd" user "Package Geometry/Place Bound Top")
		(29 "B.CrtYd" user "Package Geometry/Place Bound Bottom")
		(35 "F.Fab" user "Ref Des/Assembly Top")
		(33 "B.Fab" user "Ref Des/Assembly Bottom")
	)
	(footprint ""
		(layer "B.Cu")
		(at 29.699458 -5.621782 90)
		(property "Reference" "J9U2"
			(at 2.098548 38.118542 0)
			(unlocked yes)
			(layer "B.SilkS")
			(effects
				(font
					(size 0.7874 0.5842)
					(thickness 0.1524)
				)
				(justify left mirror)
			)
		)
		(property "Value" ""
			(at 0 0 90)
			(layer "B.Fab")
			(effects
				(font
					(size 1.27 1.27)
				)
				(justify mirror)
			)
		)
		(duplicate_pad_numbers_are_jumpers no)
		(pad "149" smd rect
			(at -4.59994 3.400044 270)
			(size 1.8034 0.508)
			(layers "B.Cu" "B.Mask" "B.Paste")
			(net "GND")
		)
		(pad "150" smd rect
			(at -4.59994 4.249928 270)
			(size 1.8034 0.508)
			(layers "B.Cu" "B.Mask" "B.Paste")
			(net "M_J_DQ<1>")
		)
		(pad "151" smd rect
			(at -4.59994 5.100066 270)
			(size 1.8034 0.508)
			(layers "B.Cu" "B.Mask" "B.Paste")
			(net "GND")
		)
		(pad "152" smd rect
			(at -4.59994 5.94995 270)
			(size 1.8034 0.508)
			(layers "B.Cu" "B.Mask" "B.Paste")
			(net "M_J_DQS_DN<0>")
		)
		(pad "153" smd rect
			(at -4.59994 6.800088 270)
			(size 1.8034 0.508)
			(layers "B.Cu" "B.Mask" "B.Paste")
			(net "M_J_DQS_DP<0>")
		)
		(pad "154" smd rect
			(at -4.59994 7.649972 270)
			(size 1.8034 0.508)
			(layers "B.Cu" "B.Mask" "B.Paste")
			(net "GND")
		)
		(pad "155" smd rect
			(at -4.59994 8.50011 270)
			(size 1.8034 0.508)
			(layers "B.Cu" "B.Mask" "B.Paste")
			(net "M_J_DQ<7>")
		)
		(pad "156" smd rect
			(at -4.59994 9.349994 270)
			(size 1.8034 0.508)
			(layers "B.Cu" "B.Mask" "B.Paste")
			(net "GND")
		)
		(pad "157" smd rect
			(at -4.59994 10.199878 270)
			(size 1.8034 0.508)
			(layers "B.Cu" "B.Mask" "B.Paste")
			(net "M_J_DQ<3>")
		)
		(pad "158" smd rect
			(at -4.59994 11.050016 270)
			(size 1.8034 0.508)
			(layers "B.Cu" "B.Mask" "B.Paste")
			(net "GND")
		)
		(pad "159" smd rect
			(at -4.59994 11.8999 270)
			(size 1.8034 0.508)
			(layers "B.Cu" "B.Mask" "B.Paste")
			(net "M_J_DQ<13>")
		)
		(pad "160" smd rect
			(at -4.59994 12.750038 270)
			(size 1.8034 0.508)
			(layers "B.Cu" "B.Mask" "B.Paste")
			(net "GND")
		)
		(pad "161" smd rect
			(at -4.59994 13.599922 270)
			(size 1.8034 0.508)
			(layers "B.Cu" "B.Mask" "B.Paste")
			(net "M_J_DQ<9>")
		)
		(pad "162" smd rect
			(at -4.59994 14.45006 270)
			(size 1.8034 0.508)
			(layers "B.Cu" "B.Mask" "B.Paste")
			(net "GND")
		)
		(pad "163" smd rect
			(at -4.59994 15.299944 270)
			(size 1.8034 0.508)
			(layers "B.Cu" "B.Mask" "B.Paste")
			(net "M_J_DQS_DN<1>")
		)
		(pad "164" smd rect
			(at -4.59994 16.150082 270)
			(size 1.8034 0.508)
			(layers "B.Cu" "B.Mask" "B.Paste")
			(net "M_J_DQS_DP<1>")
		)
		(pad "165" smd rect
			(at -4.59994 16.999966 270)
			(size 1.8034 0.508)
			(layers "B.Cu" "B.Mask" "B.Paste")
			(net "GND")
		)
		(pad "166" smd rect
			(at -4.59994 17.850104 270)
			(size 1.8034 0.508)
			(layers "B.Cu" "B.Mask" "B.Paste")
			(net "M_J_DQ<15>")
		)
		(pad "167" smd rect
			(at -4.59994 18.699988 270)
			(size 1.8034 0.508)
			(layers "B.Cu" "B.Mask" "B.Paste")
			(net "GND")
		)
		(pad "168" smd rect
			(at -4.59994 19.550126 270)
			(size 1.8034 0.508)
			(layers "B.Cu" "B.Mask" "B.Paste")
			(net "M_J_DQ<11>")
		)
		(pad "169" smd rect
			(at -4.59994 20.40001 270)
			(size 1.8034 0.508)
			(layers "B.Cu" "B.Mask" "B.Paste")
			(net "GND")
		)
		(pad "170" smd rect
			(at -4.59994 21.249894 270)
			(size 1.8034 0.508)
			(layers "B.Cu" "B.Mask" "B.Paste")
			(net "M_J_DQ<21>")
		)
		(pad "171" smd rect
			(at -4.59994 22.100032 270)
			(size 1.8034 0.508)
			(layers "B.Cu" "B.Mask" "B.Paste")
			(net "GND")
		)
		(pad "172" smd rect
			(at -4.59994 22.949916 270)
			(size 1.8034 0.508)
			(layers "B.Cu" "B.Mask" "B.Paste")
			(net "M_J_DQ<17>")
		)
		(pad "173" smd rect
			(at -4.59994 23.800054 270)
			(size 1.8034 0.508)
			(layers "B.Cu" "B.Mask" "B.Paste")
			(net "GND")
		)
		(pad "174" smd rect
			(at -4.59994 24.649938 270)
			(size 1.8034 0.508)
			(layers "B.Cu" "B.Mask" "B.Paste")
			(net "M_J_DQS_DN<2>")
		)
		(pad "175" smd rect
			(at -4.59994 25.500076 270)
			(size 1.8034 0.508)
			(layers "B.Cu" "B.Mask" "B.Paste")
			(net "M_J_DQS_DP<2>")
		)
		(pad "176" smd rect
			(at -4.59994 26.34996 270)
			(size 1.8034 0.508)
			(layers "B.Cu" "B.Mask" "B.Paste")
			(net "GND")
		)
		(pad "177" smd rect
			(at -4.59994 27.200098 270)
			(size 1.8034 0.508)
			(layers "B.Cu" "B.Mask" "B.Paste")
			(net "M_J_DQ<23>")
		)
		(pad "178" smd rect
			(at -4.59994 28.049982 270)
			(size 1.8034 0.508)
			(layers "B.Cu" "B.Mask" "B.Paste")
			(net "GND")
		)
		(pad "179" smd rect
			(at -4.59994 28.90012 270)
			(size 1.8034 0.508)
			(layers "B.Cu" "B.Mask" "B.Paste")
			(net "M_J_DQ<19>")
		)
		(pad "180" smd rect
			(at -4.59994 29.750004 270)
			(size 1.8034 0.508)
			(layers "B.Cu" "B.Mask" "B.Paste")
			(net "GND")
		)
		(pad "181" smd rect
			(at -4.59994 30.599888 270)
			(size 1.8034 0.508)
			(layers "B.Cu" "B.Mask" "B.Paste")
			(net "M_J_DQ<29>")
		)
		(pad "182" smd rect
			(at -4.59994 31.450026 270)
			(size 1.8034 0.508)
			(layers "B.Cu" "B.Mask" "B.Paste")
			(net "GND")
		)
		(pad "183" smd rect
			(at -4.59994 32.29991 270)
			(size 1.8034 0.508)
			(layers "B.Cu" "B.Mask" "B.Paste")
			(net "M_J_DQ<25>")
		)
		(pad "184" smd rect
			(at -4.59994 33.150048 270)
			(size 1.8034 0.508)
			(layers "B.Cu" "B.Mask" "B.Paste")
			(net "GND")
		)
		(pad "185" smd rect
			(at -4.59994 33.999932 270)
			(size 1.8034 0.508)
			(layers "B.Cu" "B.Mask" "B.Paste")
			(net "M_J_DQS_DN<3>")
		)
		(pad "186" smd rect
			(at -4.59994 34.85007 270)
			(size 1.8034 0.508)
			(layers "B.Cu" "B.Mask" "B.Paste")
			(net "M_J_DQS_DP<3>")
		)
		(pad "187" smd rect
			(at -4.59994 35.699954 270)
			(size 1.8034 0.508)
			(layers "B.Cu" "B.Mask" "B.Paste")
			(net "GND")
		)
		(pad "188" smd rect
			(at -4.59994 36.550092 270)
			(size 1.8034 0.508)
			(layers "B.Cu" "B.Mask" "B.Paste")
			(net "M_J_DQ<31>")
		)
		(pad "189" smd rect
			(at -4.59994 37.399976 270)
			(size 1.8034 0.508)
			(layers "B.Cu" "B.Mask" "B.Paste")
			(net "GND")
		)
		(pad "190" smd rect
			(at -4.59994 38.250114 270)
			(size 1.8034 0.508)
			(layers "B.Cu" "B.Mask" "B.Paste")
			(net "M_J_DQ<27>")
		)
		(pad "191" smd rect
			(at -4.59994 39.099998 270)
			(size 1.8034 0.508)
			(layers "B.Cu" "B.Mask" "B.Paste")
			(net "GND")
		)
		(pad "192" smd rect
			(at -4.59994 39.949882 270)
			(size 1.8034 0.508)
			(layers "B.Cu" "B.Mask" "B.Paste")
			(net "M_J_ECC<5>")
		)
		(pad "193" smd rect
			(at -4.59994 40.80002 270)
			(size 1.8034 0.508)
			(layers "B.Cu" "B.Mask" "B.Paste")
			(net "GND")
		)
		(pad "194" smd rect
			(at -4.59994 41.649904 270)
			(size 1.8034 0.508)
			(layers "B.Cu" "B.Mask" "B.Paste")
			(net "M_J_ECC<1>")
		)
		(pad "195" smd rect
			(at -4.59994 42.500042 270)
			(size 1.8034 0.508)
			(layers "B.Cu" "B.Mask" "B.Paste")
			(net "GND")
		)
		(pad "196" smd rect
			(at -4.59994 43.349926 270)
			(size 1.8034 0.508)
			(layers "B.Cu" "B.Mask" "B.Paste")
			(net "M_J_DQS_DN<8>")
		)
		(pad "197" smd rect
			(at -4.59994 44.200064 270)
			(size 1.8034 0.508)
			(layers "B.Cu" "B.Mask" "B.Paste")
			(net "M_J_DQS_DP<8>")
		)
		(pad "198" smd rect
			(at -4.59994 45.049948 270)
			(size 1.8034 0.508)
			(layers "B.Cu" "B.Mask" "B.Paste")
			(net "GND")
		)
	)
)
